;LEADER: 12 
;HEADER: 
;CODE  : ASCII 
;FILE  : 9052_F0T_PDB_Converter_Brick_F_V03_1208_1600-1-10.drl for  ... layers TOP and BOTTOM
;DESIGN: 9052_F0T_PDB_Converter_Brick_F_V03_1208_1600.brd
;   Holesize 1. = 10.000000 Tolerance = +0.000000/-10.000000 PLATED MILS Quantity = 1753
;   Holesize 2. = 34.000000 Tolerance = +3.000000/-3.000000 PLATED MILS Quantity = 16
;   Holesize 3. = 36.000000 Tolerance = +3.000000/-3.000000 PLATED MILS Quantity = 28
;   Holesize 4. = 40.000000 Tolerance = +3.000000/-3.000000 PLATED MILS Quantity = 24
;   Holesize 5. = 40.150000 Tolerance = +2.000000/-2.000000 PLATED MILS Quantity = 144
;   Holesize 6. = 41.000000 Tolerance = +3.000000/-3.000000 PLATED MILS Quantity = 16
;   Holesize 7. = 42.000000 Tolerance = +3.000000/-3.000000 PLATED MILS Quantity = 24
;   Holesize 8. = 46.000000 Tolerance = +3.000000/-3.000000 PLATED MILS Quantity = 6
;   Holesize 9. = 63.000000 Tolerance = +3.000000/-3.000000 PLATED MILS Quantity = 12
;   Holesize 10. = 67.000000 Tolerance = +3.000000/-3.000000 PLATED MILS Quantity = 12
;   Holesize 11. = 83.000000 Tolerance = +3.000000/-3.000000 PLATED MILS Quantity = 16
;   Holesize 12. = 119.000000 Tolerance = +3.000000/-3.000000 PLATED MILS Quantity = 6
;   Holesize 13. = 167.000000 Tolerance = +3.000000/-3.000000 PLATED MILS Quantity = 2
;   Holesize 14. = 252.000000 Tolerance = +4.000000/-4.000000 PLATED MILS Quantity = 2
;   Holesize 15. = 87.000000 Tolerance = +2.000000/-2.000000 NON_PLATED MILS Quantity = 2
;   Holesize 16. = 125.000000 Tolerance = +2.000000/-0.000000 NON_PLATED MILS Quantity = 3
;   Holesize 17. = 126.000000 Tolerance = +2.000000/-2.000000 NON_PLATED MILS Quantity = 6
;   Holesize 18. = 156.000000 Tolerance = +2.000000/-2.000000 NON_PLATED MILS Quantity = 6
%
G90
X0003005Y0059808
X0003005Y0034808
X0003005Y0019808
X0014811Y0003732
X0034582Y0003004
X0054582Y0003004
X0074582Y0003004
X0003005Y0145238
X0007595Y0128373
X0027271Y0127298
X0012767Y0072072
X0003005Y0245238
X0003005Y0225238
X0003005Y0205238
X0003005Y0185238
X0003005Y0165238
X0063436Y0353962
X0003005Y0345238
X0003005Y0325238
X0003005Y0305238
X0003005Y0285238
X0003005Y0265238
X0039549Y0454916
X0019558Y0454589
X0003005Y0445238
X0003005Y0425238
X0003005Y0405238
X0003005Y0385238
X0003005Y0365238
X0003023Y0549312
X0003023Y0524312
X0009913Y0510026
X0004540Y0566003
X0060498Y0575739
X0040498Y0575739
X0020498Y0575739
X0140498Y0575739
X0120498Y0575739
X0100498Y0575739
X0080498Y0575739
X0171939Y0518000
X0168939Y0518000
X0171939Y0498000
X0168939Y0498000
X0115700Y0426700
X0115700Y0423700
X0119500Y0423600
X0123000Y0423600
X0119500Y0426600
X0123000Y0426600
X0115700Y0414600
X0115700Y0411600
X0115700Y0408600
X0115700Y0417600
X0115700Y0420600
X0123000Y0420500
X0119500Y0420500
X0123000Y0417500
X0119500Y0417500
X0123000Y0408500
X0119500Y0408500
X0123000Y0411500
X0119500Y0411500
X0119500Y0414500
X0123000Y0414500
X0163800Y0423700
X0163800Y0426700
X0156800Y0426600
X0160300Y0426600
X0156800Y0423600
X0160300Y0423600
X0164000Y0408600
X0164000Y0411600
X0164000Y0420600
X0164000Y0417600
X0164000Y0414600
X0157000Y0408500
X0160500Y0408500
X0157000Y0411500
X0160500Y0411500
X0157000Y0420500
X0160500Y0420500
X0157000Y0417500
X0160500Y0417500
X0160500Y0414500
X0157000Y0414500
X0161400Y0323200
X0111600Y0261560
X0108600Y0261560
X0143400Y0261360
X0140400Y0261360
X0173265Y0340552
X0160017Y0237764
X0175481Y0225183
X0173869Y0228168
X0175976Y0218775
X0178265Y0213443
X0166068Y0238749
X0111600Y0255560
X0108600Y0255560
X0111600Y0258560
X0108600Y0258560
X0150634Y0219063
X0155034Y0231563
X0152334Y0230063
X0152334Y0226563
X0152334Y0223063
X0155034Y0224563
X0155034Y0228063
X0169840Y0247805
X0165840Y0247805
X0154840Y0244730
X0164760Y0209850
X0167660Y0209850
X0164760Y0213050
X0167660Y0213050
X0174660Y0202650
X0174660Y0205850
X0176560Y0197050
X0162850Y0223642
X0162850Y0220098
X0165350Y0230728
X0165350Y0227185
X0165350Y0220098
X0165350Y0223642
X0162850Y0230728
X0162850Y0227185
X0172934Y0219110
X0143400Y0255360
X0140400Y0255360
X0143400Y0258360
X0140400Y0258360
X0172712Y0222263
X0153480Y0213350
X0155140Y0240230
X0194582Y0003004
X0214582Y0003004
X0234582Y0003004
X0254582Y0003004
X0274582Y0003004
X0094582Y0003004
X0114582Y0003004
X0134582Y0003004
X0154582Y0003004
X0174582Y0003004
X0183900Y0216830
X0179460Y0197050
X0182260Y0197050
X0185260Y0208350
X0185260Y0205350
X0197160Y0208200
X0197160Y0205200
X0200160Y0208200
X0200160Y0205200
X0194160Y0208200
X0194160Y0205200
X0184349Y0212651
X0183815Y0220903
X0201760Y0245100
X0201760Y0242100
X0198760Y0245100
X0198760Y0242100
X0195760Y0245100
X0195760Y0242100
X0192760Y0245100
X0192760Y0242100
X0189760Y0245100
X0189760Y0242100
X0242500Y0247500
X0242500Y0243000
X0246000Y0238500
X0246000Y0235500
X0221425Y0313000
X0230425Y0313605
X0212925Y0315500
X0235975Y0309500
X0226975Y0309500
X0218500Y0309500
X0203575Y0297500
X0247441Y0305975
X0277219Y0271078
X0277219Y0275078
X0277219Y0279078
X0277219Y0283078
X0239567Y0305975
X0235975Y0305000
X0226975Y0305000
X0218500Y0305000
X0208071Y0305975
X0223819Y0445025
X0219939Y0518000
X0216939Y0518000
X0219939Y0498000
X0216939Y0498000
X0267939Y0518000
X0264939Y0518000
X0267939Y0498000
X0264939Y0498000
X0276539Y0498000
X0276539Y0518000
X0231539Y0498000
X0228539Y0498000
X0228539Y0518000
X0231539Y0518000
X0183539Y0498000
X0180539Y0498000
X0180539Y0518000
X0183539Y0518000
X0329419Y0518000
X0326419Y0518000
X0329419Y0498000
X0326419Y0498000
X0377419Y0518000
X0374419Y0518000
X0377419Y0498000
X0374419Y0498000
X0341019Y0498000
X0338019Y0498000
X0338019Y0518000
X0341019Y0518000
X0279539Y0498000
X0279539Y0518000
X0375500Y0309500
X0361000Y0305975
X0281219Y0271078
X0285219Y0271078
X0281219Y0275078
X0285219Y0275078
X0281219Y0279078
X0285219Y0279078
X0285219Y0283078
X0281219Y0283078
X0313571Y0340552
X0290720Y0340338
X0365551Y0305975
X0375475Y0305000
X0283000Y0206000
X0283000Y0196000
X0283000Y0198500
X0283000Y0203500
X0304500Y0206000
X0304500Y0196000
X0304500Y0198500
X0304500Y0203500
X0326000Y0206000
X0326000Y0196000
X0326000Y0198500
X0326000Y0203500
X0347500Y0206000
X0347500Y0196000
X0347500Y0198500
X0347500Y0203500
X0369000Y0206000
X0369000Y0196000
X0369000Y0198500
X0369000Y0203500
X0361500Y0196000
X0361500Y0198500
X0361500Y0203500
X0361500Y0206000
X0340000Y0196000
X0340000Y0198500
X0340000Y0203500
X0340000Y0206000
X0318500Y0196000
X0318500Y0198500
X0318500Y0203500
X0318500Y0206000
X0297000Y0196000
X0297000Y0198500
X0297000Y0203500
X0297000Y0206000
X0394582Y0003004
X0414582Y0003004
X0434582Y0003004
X0454582Y0003004
X0474582Y0003004
X0294582Y0003004
X0314582Y0003004
X0334582Y0003004
X0354582Y0003004
X0374582Y0003004
X0390500Y0206000
X0390500Y0196000
X0390500Y0198500
X0390500Y0203500
X0412000Y0206000
X0412000Y0196000
X0412000Y0198500
X0412000Y0203500
X0398500Y0242500
X0398500Y0247000
X0402000Y0238000
X0402000Y0235000
X0426000Y0196000
X0426000Y0198500
X0426000Y0203500
X0426000Y0206000
X0404500Y0196000
X0404500Y0198500
X0404500Y0203500
X0404500Y0206000
X0383000Y0196000
X0383000Y0198500
X0383000Y0203500
X0383000Y0206000
X0382963Y0313750
X0382963Y0316400
X0392975Y0309500
X0383975Y0309500
X0404921Y0305975
X0434499Y0271186
X0438499Y0271186
X0442499Y0271186
X0434499Y0275186
X0438499Y0275186
X0442499Y0275186
X0434499Y0279186
X0438499Y0279186
X0442499Y0279186
X0442499Y0283186
X0438499Y0283186
X0434499Y0283186
X0473095Y0340339
X0447255Y0340339
X0397047Y0305975
X0393000Y0305000
X0383975Y0305000
X0432019Y0452025
X0430019Y0444260
X0381299Y0445025
X0425419Y0518000
X0422419Y0518000
X0425419Y0498000
X0422419Y0498000
X0437019Y0498000
X0434019Y0498000
X0437019Y0518000
X0434019Y0518000
X0389019Y0498000
X0386019Y0498000
X0386019Y0518000
X0389019Y0518000
X0486900Y0518000
X0483900Y0518000
X0486900Y0498000
X0483900Y0498000
X0534900Y0518000
X0531900Y0518000
X0534900Y0498000
X0531900Y0498000
X0546500Y0518000
X0543500Y0518000
X0543500Y0498000
X0546500Y0498000
X0498500Y0518000
X0495500Y0518000
X0495500Y0498000
X0498500Y0498000
X0564500Y0442000
X0562000Y0442000
X0549500Y0445024
X0538780Y0445025
X0518575Y0295500
X0539619Y0313400
X0539619Y0316400
X0551475Y0310500
X0542475Y0310500
X0533475Y0310500
X0562402Y0305975
X0545063Y0340339
X0554528Y0305975
X0551475Y0305500
X0523032Y0305975
X0542475Y0305500
X0533475Y0305500
X0552000Y0247000
X0552000Y0243500
X0555500Y0236000
X0555500Y0239000
X0647999Y0033000
X0641100Y0048100
X0638200Y0046500
X0638200Y0044000
X0640900Y0042300
X0652300Y0056800
X0655300Y0056800
X0660200Y0056800
X0663200Y0056800
X0668100Y0056800
X0671100Y0056800
X0647975Y0037000
X0676000Y0056800
X0679000Y0056800
X0594582Y0003004
X0614582Y0003004
X0634582Y0003004
X0654582Y0003004
X0674582Y0003004
X0494582Y0003004
X0514582Y0003004
X0534582Y0003004
X0554582Y0003004
X0574582Y0003004
X0590500Y0205500
X0590500Y0195500
X0590500Y0198000
X0590500Y0203000
X0612000Y0205500
X0612000Y0195500
X0612000Y0198000
X0612000Y0203000
X0633500Y0205500
X0633500Y0195500
X0633500Y0198000
X0633500Y0203000
X0655000Y0205500
X0655000Y0195500
X0655000Y0198000
X0655000Y0203000
X0676500Y0205500
X0676500Y0203000
X0676500Y0198000
X0676500Y0195500
X0669000Y0195500
X0669000Y0198000
X0669000Y0203000
X0669000Y0205500
X0626000Y0195500
X0626000Y0198000
X0626000Y0203000
X0626000Y0205500
X0647500Y0195500
X0647500Y0198000
X0647500Y0203000
X0647500Y0205500
X0604500Y0195500
X0604500Y0198000
X0604500Y0203000
X0604500Y0205500
X0676075Y0299600
X0589500Y0446500
X0587500Y0444260
X0641381Y0498000
X0644381Y0498000
X0641381Y0518000
X0644381Y0518000
X0579900Y0498000
X0582900Y0498000
X0579900Y0518000
X0582900Y0518000
X0652981Y0498000
X0655981Y0498000
X0652981Y0518000
X0655981Y0518000
X0591500Y0518000
X0594500Y0518000
X0591500Y0498000
X0594500Y0498000
X0737381Y0498000
X0740381Y0498000
X0737381Y0518000
X0740381Y0518000
X0689381Y0498000
X0692381Y0498000
X0689381Y0518000
X0692381Y0518000
X0751981Y0518000
X0748981Y0518000
X0751981Y0498000
X0748981Y0498000
X0700981Y0498000
X0703981Y0498000
X0700981Y0518000
X0703981Y0518000
X0748075Y0366500
X0742500Y0361500
X0696261Y0445024
X0732000Y0326000
X0731925Y0336000
X0707750Y0358750
X0697900Y0352500
X0735075Y0336000
X0697100Y0313400
X0735075Y0326000
X0680400Y0310500
X0779100Y0326820
X0694406Y0295500
X0742500Y0353200
X0742500Y0347700
X0702200Y0356000
X0742500Y0334500
X0742500Y0324500
X0742500Y0328500
X0708956Y0310500
X0699956Y0310500
X0690956Y0310500
X0742000Y0341500
X0724000Y0294500
X0704400Y0358600
X0719883Y0305975
X0732100Y0332400
X0700000Y0305500
X0690956Y0305500
X0708956Y0305500
X0680513Y0305975
X0712009Y0305975
X0754000Y0356957
X0754000Y0353500
X0700040Y0258960
X0716100Y0255987
X0719490Y0205500
X0719490Y0203000
X0719490Y0198000
X0719490Y0195500
X0697990Y0205500
X0697990Y0203000
X0697990Y0198000
X0697990Y0195500
X0733490Y0205500
X0733490Y0203000
X0733490Y0198000
X0733490Y0195500
X0711990Y0205500
X0711990Y0203000
X0711990Y0198000
X0711990Y0195500
X0712981Y0239000
X0712981Y0236000
X0709481Y0243500
X0709500Y0247000
X0690500Y0195500
X0690500Y0198000
X0690500Y0203000
X0690500Y0205500
X0749760Y0064100
X0752560Y0064100
X0747160Y0064000
X0706000Y0061975
X0756160Y0064000
X0758760Y0064000
X0761560Y0064000
X0794582Y0003004
X0814582Y0003004
X0834582Y0003004
X0854582Y0003004
X0874582Y0003004
X0694425Y0029500
X0707000Y0032000
X0703740Y0041000
X0703740Y0054118
X0690075Y0039500
X0749760Y0055600
X0752560Y0055600
X0747160Y0055500
X0749760Y0047100
X0752560Y0047100
X0747160Y0047000
X0749760Y0038600
X0752560Y0038600
X0747160Y0038500
X0749760Y0030100
X0752560Y0030100
X0747160Y0030000
X0750300Y0027200
X0686500Y0056800
X0683600Y0056800
X0684525Y0036500
X0684525Y0032500
X0699500Y0034500
X0696100Y0056700
X0693000Y0056600
X0689900Y0056600
X0691400Y0053300
X0694200Y0053300
X0696900Y0053300
X0758900Y0027400
X0756160Y0030000
X0758760Y0030000
X0761560Y0030000
X0756160Y0038500
X0758760Y0038500
X0761560Y0038500
X0756160Y0047000
X0758760Y0047000
X0761560Y0047000
X0756160Y0055500
X0758760Y0055500
X0761560Y0055500
X0694582Y0003004
X0714582Y0003004
X0734582Y0003004
X0754582Y0003004
X0774582Y0003004
X0863600Y0208900
X0850750Y0250750
X0790000Y0259612
X0803500Y0259525
X0849490Y0206000
X0849490Y0203500
X0849490Y0198500
X0849490Y0196000
X0797854Y0259539
X0809500Y0259430
X0845000Y0303000
X0814500Y0293000
X0793800Y0323880
X0806500Y0285500
X0786500Y0316700
X0831750Y0318250
X0868000Y0271500
X0836500Y0302500
X0861600Y0304600
X0798400Y0323900
X0853000Y0303500
X0853500Y0268575
X0808425Y0344000
X0816000Y0270525
X0864500Y0358500
X0808425Y0334000
X0821000Y0270525
X0806000Y0265075
X0792000Y0358000
X0833500Y0268575
X0843500Y0268575
X0843843Y0354342
X0819500Y0318500
X0827602Y0283500
X0827000Y0352500
X0794900Y0265979
X0784855Y0265184
X0811575Y0344000
X0829500Y0354925
X0856000Y0270525
X0826000Y0270525
X0836000Y0270500
X0803900Y0279425
X0808500Y0276075
X0831000Y0270500
X0851000Y0270525
X0846000Y0270525
X0841000Y0270500
X0854825Y0330925
X0803000Y0346500
X0874000Y0358475
X0800575Y0338000
X0803000Y0357000
X0823500Y0329000
X0815500Y0329000
X0811500Y0329000
X0875000Y0304525
X0870000Y0304525
X0839692Y0329592
X0850500Y0356925
X0848500Y0335800
X0867000Y0291260
X0878000Y0358475
X0844760Y0336077
X0835610Y0355590
X0813975Y0357000
X0825941Y0339560
X0786500Y0336484
X0827500Y0329000
X0819500Y0329000
X0865000Y0313200
X0837575Y0321000
X0856000Y0260525
X0851000Y0260525
X0846000Y0260525
X0841000Y0260525
X0826000Y0260525
X0836000Y0260500
X0831000Y0260500
X0808500Y0272925
X0848075Y0306500
X0877500Y0283475
X0875000Y0347273
X0870000Y0312788
X0869000Y0360500
X0802975Y0362000
X0827000Y0360475
X0868542Y0385771
X0877405Y0385771
X0874405Y0385771
X0865542Y0385771
X0856253Y0385878
X0859253Y0385878
X0847390Y0385878
X0850390Y0385878
X0862342Y0416916
X0865342Y0416916
X0856342Y0416916
X0859342Y0416916
X0853619Y0405097
X0853619Y0408097
X0859342Y0408150
X0859342Y0405150
X0856342Y0408150
X0856342Y0405150
X0865342Y0405150
X0865342Y0408150
X0862342Y0405150
X0862342Y0408150
X0868342Y0408150
X0868342Y0405150
X0871342Y0408150
X0871342Y0405150
X0814323Y0411150
X0817153Y0411096
X0817153Y0413862
X0814323Y0413916
X0817153Y0416862
X0814323Y0416916
X0814323Y0408150
X0814323Y0405150
X0817153Y0405096
X0817153Y0408096
X0796600Y0416863
X0796600Y0413863
X0796600Y0411097
X0802323Y0411150
X0799323Y0411150
X0808323Y0411150
X0805323Y0411150
X0811323Y0411150
X0811323Y0413916
X0805323Y0413916
X0808323Y0413916
X0799323Y0413916
X0802323Y0413916
X0811323Y0416916
X0805323Y0416916
X0808323Y0416916
X0799323Y0416916
X0802323Y0416916
X0796600Y0405097
X0796600Y0408097
X0802323Y0408150
X0802323Y0405150
X0799323Y0408150
X0799323Y0405150
X0808323Y0405150
X0808323Y0408150
X0805323Y0405150
X0805323Y0408150
X0811323Y0408150
X0811323Y0405150
X0874172Y0411096
X0874172Y0413862
X0874172Y0416862
X0874172Y0405096
X0874172Y0408096
X0853619Y0416863
X0853619Y0413863
X0853619Y0411097
X0859342Y0411150
X0856342Y0411150
X0865342Y0411150
X0862342Y0411150
X0868342Y0411150
X0871342Y0411150
X0871342Y0413916
X0868342Y0413916
X0862342Y0413916
X0865342Y0413916
X0856342Y0413916
X0859342Y0413916
X0871342Y0416916
X0868342Y0416916
X0849000Y0399000
X0781500Y0362700
X0813975Y0362000
X0868500Y0366000
X0874500Y0366000
X0877500Y0366000
X0865500Y0366000
X0859500Y0366000
X0856500Y0366000
X0847500Y0366000
X0850500Y0366000
X0850500Y0360075
X0874257Y0483503
X0871257Y0477684
X0871257Y0480503
X0871257Y0474684
X0871257Y0483503
X0874257Y0474684
X0874257Y0480503
X0874257Y0477684
X0874311Y0486332
X0871311Y0486332
X0865257Y0477684
X0865257Y0480503
X0865257Y0474684
X0868257Y0474684
X0868257Y0480503
X0868257Y0477684
X0865257Y0483503
X0868257Y0483503
X0865311Y0486332
X0868311Y0486332
X0842434Y0508464
X0845263Y0505410
X0842434Y0505464
X0845263Y0502410
X0842434Y0502464
X0851082Y0502410
X0848263Y0502410
X0854082Y0502410
X0851082Y0523410
X0848263Y0523410
X0854082Y0523410
X0842434Y0520464
X0845263Y0520410
X0845263Y0517410
X0842434Y0517464
X0845263Y0514410
X0842434Y0514464
X0845263Y0511410
X0842434Y0511464
X0845263Y0508410
X0854082Y0520410
X0848263Y0520410
X0851082Y0520410
X0851082Y0517410
X0848263Y0517410
X0854082Y0517410
X0851082Y0514410
X0848263Y0514410
X0854082Y0514410
X0851082Y0511410
X0848263Y0511410
X0854082Y0511410
X0851082Y0508410
X0848263Y0508410
X0854082Y0508410
X0851082Y0505410
X0848263Y0505410
X0854082Y0505410
X0845263Y0523410
X0842434Y0523464
X0802709Y0486332
X0799655Y0483503
X0799709Y0486332
X0796655Y0483503
X0796709Y0486332
X0796655Y0477684
X0796655Y0480503
X0796655Y0474684
X0817655Y0477684
X0817655Y0480503
X0817655Y0474684
X0814709Y0486332
X0814655Y0483503
X0811655Y0483503
X0811709Y0486332
X0808655Y0483503
X0808709Y0486332
X0805655Y0483503
X0805709Y0486332
X0802655Y0483503
X0814655Y0474684
X0814655Y0480503
X0814655Y0477684
X0811655Y0477684
X0811655Y0480503
X0811655Y0474684
X0808655Y0477684
X0808655Y0480503
X0808655Y0474684
X0805655Y0477684
X0805655Y0480503
X0805655Y0474684
X0802655Y0477684
X0802655Y0480503
X0802655Y0474684
X0799655Y0477684
X0799655Y0480503
X0799655Y0474684
X0817655Y0483503
X0817709Y0486332
X0859311Y0486332
X0856257Y0483503
X0856311Y0486332
X0853257Y0483503
X0853311Y0486332
X0853257Y0477684
X0853257Y0480503
X0853257Y0474684
X0862257Y0483503
X0862311Y0486332
X0859257Y0483503
X0862257Y0477684
X0862257Y0480503
X0862257Y0474684
X0859257Y0477684
X0859257Y0480503
X0859257Y0474684
X0856257Y0477684
X0856257Y0480503
X0856257Y0474684
X0960498Y0575739
X0940498Y0575739
X0911776Y0516184
X0914776Y0516184
X0917542Y0516184
X0920596Y0519014
X0923596Y0519014
X0911830Y0519014
X0914830Y0519014
X0917596Y0519014
X0923542Y0516184
X0920542Y0516184
X0911776Y0513184
X0914776Y0504184
X0914776Y0501184
X0914776Y0510184
X0914776Y0507184
X0914776Y0513184
X0917542Y0513184
X0917542Y0507184
X0917542Y0510184
X0917542Y0501184
X0917542Y0504184
X0917595Y0498461
X0914829Y0498461
X0911829Y0498461
X0923542Y0513184
X0920542Y0513184
X0920542Y0507184
X0923542Y0507184
X0920542Y0510184
X0923542Y0510184
X0923542Y0501184
X0920542Y0501184
X0923542Y0504184
X0920542Y0504184
X0920595Y0498461
X0923595Y0498461
X0911776Y0504184
X0911776Y0501184
X0911776Y0510184
X0911776Y0507184
X0953110Y0385877
X0950110Y0385877
X0934317Y0385771
X0931317Y0385771
X0941247Y0385877
X0944247Y0385877
X0915525Y0385877
X0925454Y0385771
X0922454Y0385771
X0903662Y0385877
X0906662Y0385877
X0912525Y0385877
X0887228Y0385771
X0884228Y0385771
X0896091Y0385771
X0893091Y0385771
X0910992Y0361075
X0927000Y0361075
X0931500Y0366000
X0953500Y0366000
X0950500Y0366000
X0934500Y0366000
X0941000Y0366000
X0944000Y0366000
X0925000Y0366000
X0922000Y0366000
X0915500Y0366000
X0912500Y0366000
X0903000Y0366000
X0906000Y0366000
X0896500Y0366000
X0893500Y0366000
X0887000Y0366000
X0884000Y0366000
X0935516Y0361075
X0923740Y0345500
X0933196Y0353360
X0903500Y0327975
X0905941Y0320366
X0943171Y0315385
X0940000Y0283800
X0888000Y0283475
X0933357Y0344843
X0880000Y0312855
X0885500Y0352925
X0880000Y0304525
X0904500Y0292000
X0943172Y0310885
X0947000Y0302475
X0937516Y0300075
X0926000Y0283475
X0943885Y0352385
X0927000Y0357925
X0920000Y0355525
X0930500Y0315460
X0912000Y0332425
X0915000Y0322425
X0909000Y0283475
X0916260Y0355000
X0883000Y0358500
X0883000Y0293925
X0893363Y0298740
X0884000Y0283475
X0894500Y0283475
X0905941Y0306500
X0905000Y0283475
X0947000Y0293476
X0940000Y0293476
X0933196Y0309910
X0914500Y0292000
X0933000Y0293476
X0915500Y0283475
X0941035Y0344474
X0908000Y0327975
X0916260Y0337077
X0912500Y0327975
X0901063Y0352340
X0940575Y0304000
X0994582Y0003004
X1014582Y0003004
X1034582Y0003004
X1054582Y0003004
X1074582Y0003004
X1063500Y0159814
X1024340Y0146600
X1077200Y0090900
X1073200Y0090900
X1022575Y0100925
X1022575Y0115500
X1017837Y0154280
X1017909Y0151424
X1022168Y0155877
X1019040Y0157310
X1070715Y0146500
X1057500Y0155877
X1043936Y0145745
X1073154Y0137800
X1073154Y0140800
X1057525Y0138600
X1057525Y0134000
X1036500Y0153500
X1048000Y0153500
X1057525Y0130500
X1037500Y0142000
X1054500Y0148500
X1037000Y0146300
X1047159Y0141487
X1049356Y0143900
X1034500Y0145000
X1068900Y0110000
X1065000Y0156425
X1067600Y0123200
X1070400Y0123200
X1073200Y0123200
X1073200Y0128800
X1073200Y0126000
X1034500Y0142000
X0894582Y0003004
X0914582Y0003004
X0934582Y0003004
X0954582Y0003004
X0974582Y0003004
X1053830Y0191670
X1058000Y0191500
X1062500Y0191500
X1022168Y0161783
X1019030Y0160330
X1019700Y0166600
X1022000Y0171200
X1039016Y0185925
X1039538Y0179208
X1039016Y0183027
X1060500Y0164500
X1073500Y0191500
X1070000Y0191500
X1067000Y0191500
X1039016Y0189075
X1036500Y0163000
X1048000Y0163000
X1036500Y0172000
X1048000Y0172000
X1016614Y0197767
X1016614Y0190267
X1016614Y0187267
X1072000Y0243000
X1072000Y0246000
X1072000Y0255000
X1072000Y0258000
X1069000Y0243000
X1069000Y0246000
X1069000Y0255000
X1069000Y0258000
X1060000Y0255000
X1063000Y0255000
X1066000Y0255000
X1060000Y0258000
X1063000Y0258000
X1066000Y0258000
X1060000Y0243000
X1063000Y0243000
X1066000Y0243000
X1060000Y0246000
X1063000Y0246000
X1066000Y0246000
X1066000Y0252000
X1063000Y0252000
X1060000Y0252000
X1066000Y0249000
X1063000Y0249000
X1060000Y0249000
X1070715Y0178585
X1061600Y0359642
X1061600Y0323742
X1061600Y0276242
X1067679Y0317942
X1067701Y0270442
X1072000Y0341000
X1072000Y0350000
X1072000Y0353000
X1069000Y0341000
X1069000Y0350000
X1069000Y0353000
X1060000Y0350000
X1063000Y0350000
X1066000Y0350000
X1060000Y0353000
X1063000Y0353000
X1066000Y0353000
X1060000Y0341000
X1063000Y0341000
X1066000Y0341000
X1066000Y0347000
X1063000Y0347000
X1060000Y0347000
X1066000Y0344000
X1063000Y0344000
X1060000Y0344000
X1072000Y0338000
X1069000Y0338000
X1060000Y0338000
X1063000Y0338000
X1066000Y0338000
X1072000Y0290500
X1072000Y0302500
X1072000Y0305500
X1072000Y0293500
X1069000Y0290500
X1060000Y0290500
X1063000Y0290500
X1066000Y0290500
X1069000Y0302500
X1069000Y0305500
X1060000Y0302500
X1063000Y0302500
X1066000Y0302500
X1060000Y0305500
X1063000Y0305500
X1066000Y0305500
X1066000Y0299500
X1063000Y0299500
X1060000Y0299500
X1069000Y0293500
X1060000Y0293500
X1063000Y0293500
X1066000Y0293500
X1066000Y0296500
X1063000Y0296500
X1060000Y0296500
X1074316Y0406925
X1060984Y0418742
X1067707Y0365442
X1067531Y0412942
X1072000Y0445000
X1072000Y0448000
X1069000Y0445000
X1069000Y0448000
X1060000Y0445000
X1063000Y0445000
X1066000Y0445000
X1060000Y0448000
X1063000Y0448000
X1066000Y0448000
X1072000Y0436000
X1072000Y0433000
X1069000Y0436000
X1060000Y0436000
X1063000Y0436000
X1066000Y0436000
X1066000Y0442000
X1063000Y0442000
X1060000Y0442000
X1066000Y0439000
X1063000Y0439000
X1060000Y0439000
X1069000Y0433000
X1060000Y0433000
X1063000Y0433000
X1066000Y0433000
X1072000Y0385500
X1072000Y0388500
X1072000Y0400500
X1072000Y0397500
X1069000Y0385500
X1069000Y0388500
X1060000Y0385500
X1063000Y0385500
X1066000Y0385500
X1060000Y0388500
X1063000Y0388500
X1066000Y0388500
X1066000Y0394500
X1063000Y0394500
X1060000Y0394500
X1066000Y0391500
X1063000Y0391500
X1060000Y0391500
X1069000Y0400500
X1060000Y0400500
X1063000Y0400500
X1066000Y0400500
X1069000Y0397500
X1060000Y0397500
X1063000Y0397500
X1066000Y0397500
X1061600Y0513742
X1061600Y0466242
X1067730Y0460352
X1067866Y0507629
X1069500Y0553000
X1066500Y0553000
X1066500Y0550000
X1066500Y0547000
X1069500Y0550000
X1069500Y0547000
X1069500Y0538000
X1069500Y0544000
X1066500Y0544000
X1069500Y0541000
X1066500Y0541000
X1066500Y0538000
X1072000Y0495500
X1072000Y0492500
X1072000Y0483500
X1072000Y0480500
X1060000Y0486500
X1063000Y0486500
X1066000Y0486500
X1060000Y0489500
X1063000Y0489500
X1066000Y0489500
X1066000Y0483500
X1063000Y0483500
X1060000Y0483500
X1066000Y0480500
X1063000Y0480500
X1060000Y0480500
X1066000Y0495500
X1063000Y0495500
X1060000Y0495500
X1066000Y0492500
X1063000Y0492500
X1060000Y0492500
X1069000Y0495500
X1069000Y0492500
X1069000Y0483500
X1069000Y0480500
X1060498Y0575739
X1040498Y0575739
X1020498Y0575739
X1000498Y0575739
X0980498Y0575739
X1160498Y0575739
X1140498Y0575739
X1120498Y0575739
X1100498Y0575739
X1080498Y0575739
X1138622Y0467732
X1138622Y0485732
X1138622Y0470732
X1138622Y0479732
X1138622Y0476732
X1138622Y0473732
X1138622Y0482732
X1123554Y0473912
X1135622Y0482732
X1135622Y0473732
X1135622Y0476732
X1135622Y0479732
X1135622Y0467732
X1135622Y0470732
X1135622Y0485732
X1120671Y0474019
X1114799Y0474019
X1111916Y0474126
X1106683Y0474232
X1103800Y0474339
X1156799Y0460537
X1159799Y0460537
X1162799Y0460537
X1156799Y0463537
X1159799Y0463537
X1162799Y0463537
X1177925Y0491734
X1165190Y0471250
X1120669Y0547000
X1123669Y0547000
X1120669Y0550000
X1123669Y0550000
X1120669Y0553000
X1123669Y0553000
X1120669Y0538000
X1123669Y0538000
X1123669Y0541000
X1123669Y0544000
X1120669Y0541000
X1120669Y0544000
X1111452Y0547000
X1114452Y0547000
X1111452Y0550000
X1114452Y0550000
X1111452Y0553000
X1114452Y0553000
X1111452Y0538000
X1114452Y0538000
X1114452Y0541000
X1114452Y0544000
X1111452Y0541000
X1111452Y0544000
X1080418Y0373600
X1135403Y0361979
X1138403Y0361979
X1156799Y0457537
X1159799Y0457537
X1162799Y0457537
X1138404Y0457228
X1138404Y0448228
X1138404Y0445228
X1138404Y0451228
X1138404Y0454228
X1135404Y0448228
X1135404Y0445228
X1135404Y0451228
X1135404Y0454228
X1135404Y0457228
X1156799Y0451537
X1159799Y0451537
X1162799Y0451537
X1156799Y0454537
X1159799Y0454537
X1162799Y0454537
X1162799Y0436537
X1159799Y0436537
X1156799Y0436537
X1156799Y0439537
X1159799Y0439537
X1162799Y0439537
X1156799Y0442537
X1159799Y0442537
X1162799Y0442537
X1156799Y0445537
X1159799Y0445537
X1162799Y0445537
X1156799Y0448537
X1159799Y0448537
X1162799Y0448537
X1138190Y0408965
X1138190Y0405965
X1138190Y0402965
X1123763Y0426818
X1135190Y0408965
X1135190Y0405965
X1135190Y0402965
X1106892Y0427138
X1112125Y0427032
X1115008Y0426925
X1120880Y0426925
X1104009Y0427245
X1138190Y0396965
X1138190Y0399965
X1135190Y0396965
X1135190Y0399965
X1086500Y0403500
X1090500Y0376500
X1090443Y0417343
X1135203Y0266860
X1135203Y0263860
X1135203Y0260860
X1138203Y0263860
X1138203Y0260860
X1138203Y0266860
X1138403Y0314360
X1138403Y0308360
X1138403Y0311360
X1121550Y0331467
X1135403Y0308360
X1135403Y0311360
X1135403Y0314360
X1138403Y0305360
X1138403Y0302360
X1121657Y0284592
X1135403Y0305360
X1135403Y0302360
X1104679Y0331787
X1109912Y0331681
X1112795Y0331574
X1118667Y0331574
X1101796Y0331894
X1104786Y0284912
X1110019Y0284806
X1112902Y0284699
X1118774Y0284699
X1101903Y0285019
X1156710Y0315037
X1159710Y0315037
X1162710Y0315037
X1156710Y0318037
X1159710Y0318037
X1162710Y0318037
X1156710Y0321037
X1159710Y0321037
X1162710Y0321037
X1156710Y0309037
X1159710Y0309037
X1162710Y0309037
X1156710Y0312037
X1159710Y0312037
X1162710Y0312037
X1162710Y0294037
X1159710Y0294037
X1156710Y0294037
X1156710Y0297037
X1159710Y0297037
X1162710Y0297037
X1156710Y0300037
X1159710Y0300037
X1162710Y0300037
X1156710Y0303037
X1159710Y0303037
X1162710Y0303037
X1156710Y0306037
X1159710Y0306037
X1162710Y0306037
X1135403Y0349979
X1138403Y0349979
X1135403Y0352979
X1138403Y0352979
X1135403Y0355979
X1138403Y0355979
X1135403Y0358979
X1138403Y0358979
X1177836Y0349234
X1086500Y0356000
X1165070Y0328750
X1108821Y0166800
X1167600Y0180500
X1167600Y0184500
X1158000Y0179000
X1152500Y0186500
X1143490Y0183560
X1140336Y0183560
X1135203Y0254860
X1135203Y0257860
X1138203Y0254860
X1138203Y0257860
X1106106Y0231741
X1106189Y0224241
X1133000Y0198000
X1085525Y0164000
X1085525Y0174500
X1085525Y0171000
X1085525Y0167500
X1079500Y0184575
X1085000Y0184575
X1129000Y0176500
X1129000Y0166500
X1120200Y0166500
X1120200Y0176500
X1177521Y0162952
X1177521Y0165952
X1114500Y0188700
X1129068Y0195500
X1117290Y0224241
X1100000Y0203700
X1097500Y0203700
X1140000Y0161100
X1140000Y0172300
X1136300Y0172300
X1136300Y0161100
X1113129Y0165719
X1110800Y0170000
X1113368Y0171619
X1108000Y0172000
X1094024Y0179500
X1123500Y0187000
X1125918Y0195418
X1117206Y0231741
X1171500Y0214000
X1171500Y0211000
X1171500Y0208000
X1171500Y0205000
X1174500Y0205000
X1174500Y0208000
X1174500Y0211000
X1174500Y0214000
X1111100Y0163749
X1152781Y0165719
X1119000Y0189500
X1087500Y0201000
X1087500Y0198000
X1160200Y0175982
X1162700Y0175959
X1084401Y0159260
X1084325Y0130197
X1115800Y0126600
X1094500Y0143144
X1092000Y0159500
X1082000Y0143600
X1115425Y0138925
X1120200Y0157000
X1129000Y0157000
X1120524Y0138457
X1104500Y0136524
X1087000Y0100000
X1108500Y0136500
X1094493Y0151856
X1121238Y0144500
X1126075Y0135973
X1158200Y0137700
X1130125Y0135940
X1131500Y0120816
X1134500Y0120816
X1126000Y0120816
X1123000Y0120816
X1092000Y0082500
X1141500Y0120500
X1141500Y0134575
X1141500Y0124425
X1154000Y0151500
X1159300Y0129700
X1084740Y0108000
X1084260Y0152600
X1100075Y0139925
X1113500Y0147500
X1119500Y0083000
X1119500Y0086000
X1113000Y0101240
X1095100Y0099500
X1091000Y0099500
X1155000Y0124913
X1137950Y0085867
X1140450Y0085867
X1142950Y0085867
X1142950Y0082867
X1140450Y0082867
X1137950Y0082867
X1135450Y0082867
X1135450Y0085867
X1132950Y0085867
X1132950Y0082867
X1177475Y0111500
X1178321Y0120652
X1178321Y0123652
X1194582Y0003004
X1214582Y0003004
X1234582Y0003004
X1254582Y0003004
X1277657Y0004128
X1125031Y0018126
X1125031Y0021126
X1127531Y0021126
X1127531Y0018126
X1130031Y0018126
X1132531Y0018126
X1132531Y0021126
X1130031Y0021126
X1135031Y0018126
X1135031Y0021126
X1106961Y0021126
X1106961Y0018126
X1101961Y0021126
X1104461Y0021126
X1104461Y0018126
X1101961Y0018126
X1099461Y0018126
X1099461Y0021126
X1096961Y0021126
X1096961Y0018126
X1107101Y0056737
X1107101Y0053737
X1102101Y0056737
X1104601Y0056737
X1104601Y0053737
X1102101Y0053737
X1099601Y0053737
X1099601Y0056737
X1097101Y0056737
X1097101Y0053737
X1107100Y0038582
X1107100Y0035582
X1102100Y0038582
X1104600Y0038582
X1104600Y0035582
X1102100Y0035582
X1099600Y0035582
X1099600Y0038582
X1097100Y0038582
X1097100Y0035582
X1130170Y0038582
X1132670Y0038582
X1135170Y0038582
X1135170Y0035582
X1132670Y0035582
X1130170Y0035582
X1127670Y0035582
X1127670Y0038582
X1125170Y0038582
X1125170Y0035582
X1179500Y0105500
X1180821Y0123652
X1180821Y0120652
X1094582Y0003004
X1114582Y0003004
X1134582Y0003004
X1154582Y0003004
X1174582Y0003004
X1183321Y0120652
X1185821Y0120652
X1188321Y0120652
X1188321Y0123652
X1185821Y0123652
X1183321Y0123652
X1180521Y0165952
X1180521Y0162952
X1183021Y0162952
X1185521Y0162952
X1188618Y0162782
X1188600Y0166000
X1185521Y0165952
X1183021Y0165952
X1179411Y0327250
X1179411Y0330750
X1180986Y0349234
X1179411Y0337750
X1179411Y0334250
X1193411Y0328750
X1179651Y0305942
X1179651Y0309942
X1197887Y0309894
X1200887Y0309894
X1203887Y0309894
X1197887Y0312894
X1200887Y0312894
X1203887Y0312894
X1197887Y0315894
X1200887Y0315894
X1203887Y0315894
X1197887Y0318894
X1200887Y0318894
X1203887Y0318894
X1203887Y0321894
X1200887Y0321894
X1197887Y0321894
X1197887Y0294894
X1200887Y0294894
X1203887Y0294894
X1197887Y0297894
X1200887Y0297894
X1203887Y0297894
X1197887Y0300894
X1200887Y0300894
X1203887Y0300894
X1197887Y0303894
X1200887Y0303894
X1203887Y0303894
X1197887Y0306894
X1200887Y0306894
X1203887Y0306894
X1179877Y0448442
X1179877Y0452442
X1203976Y0458394
X1200976Y0458394
X1197976Y0458394
X1203976Y0455394
X1200976Y0455394
X1197976Y0455394
X1203976Y0452394
X1200976Y0452394
X1197976Y0452394
X1203976Y0449394
X1200976Y0449394
X1197976Y0449394
X1203976Y0446394
X1200976Y0446394
X1197976Y0446394
X1203976Y0443394
X1200976Y0443394
X1197976Y0443394
X1203976Y0440394
X1200976Y0440394
X1197976Y0440394
X1203976Y0437394
X1200976Y0437394
X1197976Y0437394
X1179500Y0473250
X1179500Y0469750
X1179500Y0480250
X1179500Y0476750
X1181075Y0491734
X1193840Y0471250
X1203976Y0461394
X1200976Y0461394
X1197976Y0461394
X1203976Y0464394
X1200976Y0464394
X1197976Y0464394
X1260498Y0575739
X1240498Y0575739
X1220498Y0575739
X1200498Y0575739
X1180498Y0575739
X1279438Y0573806
X1287616Y0563889
X1288331Y0470962
X1288331Y0490962
X1288331Y0510962
X1288331Y0530962
X1288331Y0550962
X1288331Y0370962
X1288331Y0390962
X1288331Y0410962
X1288331Y0430962
X1288331Y0450962
X1288331Y0270962
X1288331Y0290962
X1288331Y0310962
X1288331Y0330962
X1288331Y0350962
X1288331Y0170962
X1288331Y0190962
X1288331Y0210962
X1288331Y0230962
X1288331Y0250962
X1288331Y0070962
X1288331Y0090962
X1288331Y0110962
X1288331Y0130962
X1288331Y0150962
X1286766Y0012634
X1288331Y0030962
X1288331Y0050962
M00
X0038780Y0349724
X0038780Y0339724
X0038780Y0329724
X0038780Y0319724
X0033780Y0314724
X0033780Y0324724
X0033780Y0334724
X0033780Y0344724
X0043780Y0344724
X0043780Y0334724
X0043780Y0324724
X0043780Y0314724
X0048780Y0349724
X0048780Y0339724
X0048780Y0329724
X0048780Y0319724
M00
X0239567Y0267204
X0247441Y0267204
X0223819Y0267204
X0231693Y0267204
X0215945Y0267204
X0200197Y0267204
X0208071Y0267204
X0373425Y0267204
X0357677Y0267204
X0365551Y0267204
X0397047Y0267204
X0404921Y0267204
X0381299Y0267204
X0389173Y0267204
X0554528Y0267204
X0562402Y0267204
X0538780Y0267204
X0546654Y0267204
X0530906Y0267204
X0515158Y0267204
X0523032Y0267204
X0672639Y0267204
X0712009Y0267204
X0719883Y0267204
X0696261Y0267204
X0704135Y0267204
X0688387Y0267204
X0680513Y0267204
M00
X0268000Y0220315
X0268000Y0240000
X0357000Y0220315
X0357000Y0240000
X0312500Y0220315
X0312500Y0240000
X0428500Y0220315
X0428500Y0240000
X0472500Y0220315
X0472500Y0240000
X0578500Y0220315
X0578500Y0240000
X0516500Y0220315
X0516500Y0240000
X0666500Y0220315
X0666500Y0240000
X0622500Y0220315
X0622500Y0240000
X0735981Y0220315
X0735981Y0240000
X0823981Y0220315
X0823981Y0240000
X0779981Y0220315
X0779981Y0240000
M00
X0296752Y0159685
X0296752Y0149685
X0296752Y0139685
X0296752Y0129685
X0306752Y0159685
X0306752Y0149685
X0306752Y0139685
X0306752Y0129685
X0331752Y0159685
X0331752Y0149685
X0331752Y0139685
X0331752Y0129685
X0341752Y0159685
X0341752Y0149685
X0341752Y0139685
X0341752Y0129685
X0366752Y0159685
X0366752Y0149685
X0366752Y0139685
X0366752Y0129685
X0376752Y0159685
X0376752Y0149685
X0376752Y0139685
X0376752Y0129685
X0401752Y0159685
X0401752Y0149685
X0401752Y0139685
X0401752Y0129685
X0411752Y0159685
X0411752Y0149685
X0411752Y0139685
X0411752Y0129685
X0436752Y0159685
X0436752Y0149685
X0436752Y0139685
X0436752Y0129685
X0446752Y0159685
X0446752Y0149685
X0446752Y0139685
X0446752Y0129685
X0471752Y0159685
X0471752Y0149685
X0471752Y0139685
X0471752Y0129685
X0481752Y0159685
X0481752Y0149685
X0481752Y0139685
X0481752Y0129685
X0757559Y0119408
X0757559Y0129408
X0757559Y0139408
X0757559Y0149408
X0747559Y0119408
X0747559Y0129408
X0747559Y0139408
X0747559Y0149408
X0722559Y0119408
X0722559Y0129408
X0722559Y0139408
X0722559Y0149408
X0712559Y0119408
X0712559Y0129408
X0712559Y0139408
X0712559Y0149408
X0862559Y0119408
X0862559Y0129408
X0862559Y0139408
X0862559Y0149408
X0852559Y0119408
X0852559Y0129408
X0852559Y0139408
X0852559Y0149408
X0832559Y0149408
X0832559Y0139408
X0832559Y0129408
X0832559Y0119408
X0822559Y0149408
X0822559Y0139408
X0822559Y0129408
X0822559Y0119408
X0812559Y0149408
X0812559Y0139408
X0812559Y0129408
X0812559Y0119408
X0792559Y0119408
X0792559Y0129408
X0792559Y0139408
X0792559Y0149408
X0782559Y0119408
X0782559Y0129408
X0782559Y0139408
X0782559Y0149408
X0932559Y0119408
X0932559Y0129408
X0932559Y0139408
X0932559Y0149408
X0922559Y0119408
X0922559Y0129408
X0922559Y0139408
X0922559Y0149408
X0897559Y0119408
X0897559Y0129408
X0897559Y0139408
X0897559Y0149408
X0887559Y0119408
X0887559Y0129408
X0887559Y0139408
X0887559Y0149408
X1256024Y0256929
X1246024Y0256929
X1236024Y0256929
X1226024Y0256929
X1256024Y0231929
X1246024Y0231929
X1236024Y0231929
X1226024Y0231929
X1256024Y0221929
X1246024Y0221929
X1236024Y0221929
X1226024Y0221929
X1256024Y0351929
X1246024Y0351929
X1236024Y0351929
X1226024Y0351929
X1256024Y0341929
X1246024Y0341929
X1236024Y0341929
X1226024Y0341929
X1256024Y0316929
X1246024Y0316929
X1236024Y0316929
X1226024Y0316929
X1256024Y0306929
X1246024Y0306929
X1236024Y0306929
X1226024Y0306929
X1256024Y0286929
X1246024Y0286929
X1236024Y0286929
X1226024Y0286929
X1256024Y0266929
X1246024Y0266929
X1236024Y0266929
X1226024Y0266929
M00
X0048780Y0259291
X0048780Y0252598
X0038780Y0259291
X0038780Y0252598
X0048780Y0239291
X0048780Y0232598
X0038780Y0239291
X0038780Y0232598
X0048780Y0299291
X0048780Y0292598
X0038780Y0299291
X0038780Y0292598
X0048780Y0279291
X0048780Y0272598
X0038780Y0279291
X0038780Y0272598
M00
X0165539Y0539000
X0261539Y0539000
X0233224Y0539000
X0213539Y0539000
X0185224Y0539000
X0371019Y0539000
X0342704Y0539000
X0323019Y0539000
X0281224Y0539000
X0438704Y0539000
X0419019Y0539000
X0390704Y0539000
X0576500Y0539000
X0548185Y0539000
X0528500Y0539000
X0500185Y0539000
X0480500Y0539000
X0657666Y0539000
X0637981Y0539000
X0596185Y0539000
X0753666Y0539000
X0733981Y0539000
X0705666Y0539000
X0685981Y0539000
M00
X1011000Y0098000
X1011000Y0108000
X1011000Y0118000
X1151000Y0090400
X1161000Y0090400
X1171000Y0090400
M00
X0253819Y0477204
X0223819Y0477204
X0193819Y0477204
X0351299Y0477204
X0411299Y0477204
X0381299Y0477204
X0568780Y0477204
X0538780Y0477204
X0508780Y0477204
X0666261Y0477204
X0726261Y0477204
X0696261Y0477204
M00
X0766498Y0602542
X0766498Y0612542
X0753314Y0607542
X0766604Y0640687
X0766604Y0630687
X0753420Y0635687
X1082833Y0640687
X1082833Y0630687
X1096017Y0635687
X1082833Y0602542
X1082833Y0612542
X1096017Y0607542
M00
X0178819Y0277204
X0268819Y0277204
X0253819Y0277204
X0193819Y0277204
X0351299Y0277204
X0336299Y0277204
X0426299Y0277204
X0411299Y0277204
X0568780Y0277204
X0508780Y0277204
X0493780Y0277204
X0666261Y0277204
X0651261Y0277204
X0583780Y0277204
X0741261Y0277204
X0726261Y0277204
M00
X0118111Y0535433
X0118111Y0047244
X0511811Y0047244
X0905512Y0047244
X0988500Y0228000
X1030500Y0542500
M00
X1226024Y0174429
X1226024Y0399429
M00
X1240158Y0057480
X1240158Y0521260
M00
X0019922Y0214173
X0019922Y0367716
M00
X0175000Y0100500
X0877510Y0558620
X0964460Y0016950
M00
X0249252Y0129685
X0529252Y0129685
X0665059Y0149408
X0980059Y0149408
X1226024Y0174429
X1226024Y0399429
M00
X0060630Y0099724
X0060630Y0482205
X0108858Y0482205
X0082795Y0482205
X0108858Y0099724
X0082795Y0099724
M30
